FILE_TYPE = MACRO_DRAWING;
SET COLOR_WIRE YELLOW;
SET COLOR_PROP MONO;
SET COLOR_DOT WHITE;
SET COLOR_ARC YELLOW;
SET COLOR_BODY GREEN;
SET COLOR_NOTE MONO;
SET PROP_DISPLAY VALUE;
SET PAGE_NUMBER P1;
FORCEADD INTEL_CORP_BPAGE..1
(0 0);
FORCEPROP 1 LAST CDS_CON_LAST_MODIFIED Fri Jun 16 17:47:55 2017
J 0
(-1425 325);
PAINT ORANGE (-1425 325);
DISPLAY INVISIBLE (-1425 325);
FORCEPROP 1 LAST CUSTOM_TXT_CDS <CURRENT_DESIGN_SHEET> OF <TOTAL_DESIGN_SHEETS>
J 0
(-500 25);
PAINT ORANGE (-500 25);
FORCEPROP 2 LAST CUSTOM_TXT_CDS <XR_PAGE_TITLE>
J 0
(-7890 5250);
DISPLAY 0.638298 (-7890 5250);
PAINT PINK (-7890 5250);
DISPLAY INVISIBLE (-7890 5250);
FORCEPROP 2 LAST CUSTOM_TXT_CDS <CON_LAST_MODIFIED>
J 0
(-4000 100);
PAINT ORANGE (-4000 100);
FORCEPROP 1 LAST SCH_TITLE TITLE
J 0
(-7950 50);
DISPLAY 2.468085 (-7950 50);
PAINT ORANGE (-7950 50);
DISPLAY INVISIBLE (-7950 50);
FORCEPROP 2 LAST CDS_LIB mstr_symbols
J 0
(0 0);
PAINT ORANGE (0 0);
DISPLAY INVISIBLE (0 0);
FORCEPROP 2 LAST PAGE_BORDER TRUE
J 0
(-7890 5250);
DISPLAY 0.638298 (-7890 5250);
PAINT PINK (-7890 5250);
DISPLAY INVISIBLE (-7890 5250);
FORCEPROP 1 LAST COMMENT_BODY TRUE
J 0
(12 12);
DISPLAY 0.468085 (12 12);
PAINT GREEN (12 12);
DISPLAY INVISIBLE (12 12);
FORCEPROP 2 LAST CDS_XR_PAGE_TITLE CR-1 : @BASEBOARD_FAB2_LIB.BASEBOARD_FAB2(SCH_1):PAGE1
J 0
(-7890 5250);
DISPLAY 0.638298 (-7890 5250);
PAINT PINK (-7890 5250);
DISPLAY INVISIBLE (-7890 5250);
FORCENOTE
TIOGA PASS
(-7075 3000) 0;
DISPLAY LEFT (-7075 3000);
DISPLAY 3.148936 (-7075 3000);
PAINT PURPLE (-7075 3000);
FORCENOTE
PCB NUMBER: 15126_1C
(-7200 2775) 0;
DISPLAY LEFT (-7200 2775);
DISPLAY 2.000000 (-7200 2775);
PAINT PURPLE (-7200 2775);
FORCENOTE
$CDS_IMAGE|clipboard_1.jpg|4097|2146
(-3324 2577) 0;
DISPLAY LEFT (-3324 2577);
QUIT
